(kicad_pcb
	(version 20260206)
	(generator "pcbnew")
	(generator_version "10.0")
	(general
		(thickness 1.6)
		(legacy_teardrops no)
	)
	(paper "A4")
	(title_block
		(title "01162023_DA0F0TEBIF0_F0T_Expander_BD_F_brd_V02_OCP.brd")
		(comment 1 "Grand Teton / footprints 6483-6488 of 9728")
	)
	(layers
		(0 "F.Cu" signal "TOP")
		(4 "In1.Cu" signal "GND")
		(6 "In2.Cu" signal "VCC")
		(8 "In3.Cu" signal "VCC1")
		(10 "In4.Cu" signal "GND1")
		(12 "In5.Cu" signal "IN1")
		(14 "In6.Cu" signal "GND2")
		(16 "In7.Cu" signal "IN2")
		(18 "In8.Cu" signal "GND3")
		(20 "In9.Cu" signal "IN3")
		(22 "In10.Cu" signal "GND4")
		(24 "In11.Cu" signal "IN4")
		(26 "In12.Cu" signal "GND5")
		(28 "In13.Cu" signal "IN5")
		(30 "In14.Cu" signal "GND6")
		(32 "In15.Cu" signal "IN6")
		(34 "In16.Cu" signal "GND7")
		(2 "B.Cu" signal "BOTTOM")
		(9 "F.Adhes" user "F.Adhesive")
		(11 "B.Adhes" user "B.Adhesive")
		(13 "F.Paste" user "Package Geometry/Pastemask Top")
		(15 "B.Paste" user "Package Geometry/Pastemask Bottom")
		(5 "F.SilkS" user "Ref Des/Silkscreen Top")
		(7 "B.SilkS" user "Ref Des/Silkscreen Bottom")
		(1 "F.Mask" user "Board Geometry/Soldermask Top")
		(3 "B.Mask" user "Board Geometry/Soldermask Bottom")
		(17 "Dwgs.User" user "User.Drawings")
		(19 "Cmts.User" user "User.Comments")
		(21 "Eco1.User" user "User.Eco1")
		(23 "Eco2.User" user "User.Eco2")
		(25 "Edge.Cuts" user "Board Geometry/Outline")
		(27 "Margin" user)
		(31 "F.CrtYd" user "Package Geometry/Place Bound Top")
		(29 "B.CrtYd" user "Package Geometry/Place Bound Bottom")
		(35 "F.Fab" user "Ref Des/Assembly Top")
		(33 "B.Fab" user "Ref Des/Assembly Bottom")
	)
	(footprint ""
		(layer "F.Cu")
		(at 118.956328 -32.848042 -90)
		(property "Reference" "R6054"
			(at 0 0 270)
			(layer "F.SilkS")
			(hide yes)
			(effects
				(font
					(size 1.27 1.27)
				)
			)
		)
		(property "Value" ""
			(at 0 0 270)
			(layer "F.Fab")
			(effects
				(font
					(size 1.27 1.27)
				)
			)
		)
		(duplicate_pad_numbers_are_jumpers no)
		(fp_line
			(start -0.7874 0.4064)
			(end -0.7874 -0.4064)
			(stroke
				(width 0.1524)
				(type default)
			)
			(layer "F.SilkS")
		)
		(fp_line
			(start 0.7874 0.4064)
			(end -0.7874 0.4064)
			(stroke
				(width 0.1524)
				(type default)
			)
			(layer "F.SilkS")
		)
		(fp_line
			(start -0.7874 -0.4064)
			(end 0.7874 -0.4064)
			(stroke
				(width 0.1524)
				(type default)
			)
			(layer "F.SilkS")
		)
		(fp_line
			(start 0.7874 -0.4064)
			(end 0.7874 0.4064)
			(stroke
				(width 0.1524)
				(type default)
			)
			(layer "F.SilkS")
		)
		(fp_line
			(start -0.67945 0.3048)
			(end -0.67945 -0.305054)
			(stroke
				(width 0.1)
				(type default)
			)
			(layer "F.Fab")
		)
		(fp_line
			(start -0.12065 0.3048)
			(end -0.67945 0.3048)
			(stroke
				(width 0.1)
				(type default)
			)
			(layer "F.Fab")
		)
		(fp_line
			(start 0.120396 0.3048)
			(end 0.120396 0.2794)
			(stroke
				(width 0.1)
				(type default)
			)
			(layer "F.Fab")
		)
		(fp_line
			(start 0.67945 0.3048)
			(end 0.120396 0.3048)
			(stroke
				(width 0.1)
				(type default)
			)
			(layer "F.Fab")
		)
		(fp_line
			(start -0.12065 0.2794)
			(end -0.12065 0.3048)
			(stroke
				(width 0.1)
				(type default)
			)
			(layer "F.Fab")
		)
		(fp_line
			(start 0.120396 0.2794)
			(end -0.12065 0.2794)
			(stroke
				(width 0.1)
				(type default)
			)
			(layer "F.Fab")
		)
		(fp_line
			(start -0.12065 -0.2794)
			(end 0.12065 -0.2794)
			(stroke
				(width 0.1)
				(type default)
			)
			(layer "F.Fab")
		)
		(fp_line
			(start 0.12065 -0.2794)
			(end 0.12065 -0.3048)
			(stroke
				(width 0.1)
				(type default)
			)
			(layer "F.Fab")
		)
		(fp_line
			(start 0.12065 -0.3048)
			(end 0.67945 -0.3048)
			(stroke
				(width 0.1)
				(type default)
			)
			(layer "F.Fab")
		)
		(fp_line
			(start 0.67945 -0.3048)
			(end 0.67945 0.3048)
			(stroke
				(width 0.1)
				(type default)
			)
			(layer "F.Fab")
		)
		(fp_line
			(start -0.67945 -0.305054)
			(end -0.12065 -0.305054)
			(stroke
				(width 0.1)
				(type default)
			)
			(layer "F.Fab")
		)
		(fp_line
			(start -0.12065 -0.305054)
			(end -0.12065 -0.2794)
			(stroke
				(width 0.1)
				(type default)
			)
			(layer "F.Fab")
		)
		(pad "1" smd circle
			(at -0.40005 0 270)
			(size 0 0)
			(layers "F.Cu" "F.Mask" "F.Paste")
			(net "SSD4_AUX_P3V3_EN_R")
		)
		(pad "2" smd circle
			(at 0.40005 0 270)
			(size 0 0)
			(layers "F.Cu" "F.Mask" "F.Paste")
			(net "P3V3_SSD4_CO_EN")
		)
	)
	(footprint ""
		(layer "F.Cu")
		(at 231.844596 -279.567386 180)
		(property "Reference" "R787"
			(at 0 0 180)
			(layer "F.SilkS")
			(hide yes)
			(effects
				(font
					(size 1.27 1.27)
				)
			)
		)
		(property "Value" ""
			(at 0 0 180)
			(layer "F.Fab")
			(effects
				(font
					(size 1.27 1.27)
				)
			)
		)
		(duplicate_pad_numbers_are_jumpers no)
		(fp_line
			(start 0.7874 0.4064)
			(end -0.7874 0.4064)
			(stroke
				(width 0.1524)
				(type default)
			)
			(layer "F.SilkS")
		)
		(fp_line
			(start 0.7874 -0.4064)
			(end 0.7874 0.4064)
			(stroke
				(width 0.1524)
				(type default)
			)
			(layer "F.SilkS")
		)
		(fp_line
			(start -0.7874 0.4064)
			(end -0.7874 -0.4064)
			(stroke
				(width 0.1524)
				(type default)
			)
			(layer "F.SilkS")
		)
		(fp_line
			(start -0.7874 -0.4064)
			(end 0.7874 -0.4064)
			(stroke
				(width 0.1524)
				(type default)
			)
			(layer "F.SilkS")
		)
		(fp_line
			(start 0.67945 0.3048)
			(end 0.120396 0.3048)
			(stroke
				(width 0.1)
				(type default)
			)
			(layer "F.Fab")
		)
		(fp_line
			(start 0.67945 -0.3048)
			(end 0.67945 0.3048)
			(stroke
				(width 0.1)
				(type default)
			)
			(layer "F.Fab")
		)
		(fp_line
			(start 0.12065 -0.2794)
			(end 0.12065 -0.3048)
			(stroke
				(width 0.1)
				(type default)
			)
			(layer "F.Fab")
		)
		(fp_line
			(start 0.12065 -0.3048)
			(end 0.67945 -0.3048)
			(stroke
				(width 0.1)
				(type default)
			)
			(layer "F.Fab")
		)
		(fp_line
			(start 0.120396 0.3048)
			(end 0.120396 0.2794)
			(stroke
				(width 0.1)
				(type default)
			)
			(layer "F.Fab")
		)
		(fp_line
			(start 0.120396 0.2794)
			(end -0.12065 0.2794)
			(stroke
				(width 0.1)
				(type default)
			)
			(layer "F.Fab")
		)
		(fp_line
			(start -0.12065 0.3048)
			(end -0.67945 0.3048)
			(stroke
				(width 0.1)
				(type default)
			)
			(layer "F.Fab")
		)
		(fp_line
			(start -0.12065 0.2794)
			(end -0.12065 0.3048)
			(stroke
				(width 0.1)
				(type default)
			)
			(layer "F.Fab")
		)
		(fp_line
			(start -0.12065 -0.2794)
			(end 0.12065 -0.2794)
			(stroke
				(width 0.1)
				(type default)
			)
			(layer "F.Fab")
		)
		(fp_line
			(start -0.12065 -0.305054)
			(end -0.12065 -0.2794)
			(stroke
				(width 0.1)
				(type default)
			)
			(layer "F.Fab")
		)
		(fp_line
			(start -0.67945 0.3048)
			(end -0.67945 -0.305054)
			(stroke
				(width 0.1)
				(type default)
			)
			(layer "F.Fab")
		)
		(fp_line
			(start -0.67945 -0.305054)
			(end -0.12065 -0.305054)
			(stroke
				(width 0.1)
				(type default)
			)
			(layer "F.Fab")
		)
		(pad "1" smd circle
			(at -0.40005 0 180)
			(size 0 0)
			(layers "F.Cu" "F.Mask" "F.Paste")
			(net "SMB_BIC_I2C6_MUX_PEX_ADC_R_SDA")
		)
		(pad "2" smd circle
			(at 0.40005 0 180)
			(size 0 0)
			(layers "F.Cu" "F.Mask" "F.Paste")
			(net "SMB_PEX1_P1V25_ADC_SDA")
		)
	)
	(footprint ""
		(layer "F.Cu")
		(at 113.716816 -137.43686 -90)
		(property "Reference" "PC38"
			(at 0 0 270)
			(layer "F.SilkS")
			(hide yes)
			(effects
				(font
					(size 1.27 1.27)
				)
			)
		)
		(property "Value" ""
			(at 0 0 270)
			(layer "F.Fab")
			(effects
				(font
					(size 1.27 1.27)
				)
			)
		)
		(duplicate_pad_numbers_are_jumpers no)
		(fp_line
			(start -1.988058 2.750058)
			(end 2.750058 2.750058)
			(stroke
				(width 0.1524)
				(type default)
			)
			(layer "F.SilkS")
		)
		(fp_line
			(start 2.750058 2.750058)
			(end 2.750058 0.9398)
			(stroke
				(width 0.1524)
				(type default)
			)
			(layer "F.SilkS")
		)
		(fp_line
			(start -2.750058 1.988058)
			(end -1.988058 2.750058)
			(stroke
				(width 0.1524)
				(type default)
			)
			(layer "F.SilkS")
		)
		(fp_line
			(start -2.750058 0.9398)
			(end -2.750058 1.988058)
			(stroke
				(width 0.1524)
				(type default)
			)
			(layer "F.SilkS")
		)
		(fp_line
			(start 2.750058 -0.9398)
			(end 2.750058 -2.750058)
			(stroke
				(width 0.1524)
				(type default)
			)
			(layer "F.SilkS")
		)
		(fp_line
			(start -2.750058 -1.988058)
			(end -2.750058 -0.9398)
			(stroke
				(width 0.1524)
				(type default)
			)
			(layer "F.SilkS")
		)
		(fp_line
			(start -1.988058 -2.750058)
			(end -2.750058 -1.988058)
			(stroke
				(width 0.1524)
				(type default)
			)
			(layer "F.SilkS")
		)
		(fp_line
			(start 2.750058 -2.750058)
			(end -1.988058 -2.750058)
			(stroke
				(width 0.1524)
				(type default)
			)
			(layer "F.SilkS")
		)
		(fp_line
			(start -2.750058 2.750058)
			(end 2.750058 2.750058)
			(stroke
				(width 0.1)
				(type default)
			)
			(layer "F.Fab")
		)
		(fp_line
			(start 2.750058 2.750058)
			(end 2.750058 -2.750058)
			(stroke
				(width 0.1)
				(type default)
			)
			(layer "F.Fab")
		)
		(fp_line
			(start -2.750058 -2.750058)
			(end -2.750058 2.750058)
			(stroke
				(width 0.1)
				(type default)
			)
			(layer "F.Fab")
		)
		(fp_line
			(start 2.750058 -2.750058)
			(end -2.750058 -2.750058)
			(stroke
				(width 0.1)
				(type default)
			)
			(layer "F.Fab")
		)
		(pad "1" smd rect
			(at -2.199894 0)
			(size 1.6002 3.0226)
			(layers "F.Cu" "F.Mask" "F.Paste")
			(net "P3V3_AUX")
		)
		(pad "2" smd rect
			(at 2.199894 0)
			(size 1.6002 3.0226)
			(layers "F.Cu" "F.Mask" "F.Paste")
			(net "GND")
		)
	)
	(footprint ""
		(layer "F.Cu")
		(at 148.511514 -299.645832 -90)
		(property "Reference" "R4569"
			(at 0 0 270)
			(layer "F.SilkS")
			(hide yes)
			(effects
				(font
					(size 1.27 1.27)
				)
			)
		)
		(property "Value" ""
			(at 0 0 270)
			(layer "F.Fab")
			(effects
				(font
					(size 1.27 1.27)
				)
			)
		)
		(duplicate_pad_numbers_are_jumpers no)
		(fp_line
			(start -0.7874 0.4064)
			(end -0.7874 -0.4064)
			(stroke
				(width 0.1524)
				(type default)
			)
			(layer "F.SilkS")
		)
		(fp_line
			(start 0.7874 0.4064)
			(end -0.7874 0.4064)
			(stroke
				(width 0.1524)
				(type default)
			)
			(layer "F.SilkS")
		)
		(fp_line
			(start -0.7874 -0.4064)
			(end 0.7874 -0.4064)
			(stroke
				(width 0.1524)
				(type default)
			)
			(layer "F.SilkS")
		)
		(fp_line
			(start 0.7874 -0.4064)
			(end 0.7874 0.4064)
			(stroke
				(width 0.1524)
				(type default)
			)
			(layer "F.SilkS")
		)
		(fp_line
			(start -0.67945 0.3048)
			(end -0.67945 -0.305054)
			(stroke
				(width 0.1)
				(type default)
			)
			(layer "F.Fab")
		)
		(fp_line
			(start -0.12065 0.3048)
			(end -0.67945 0.3048)
			(stroke
				(width 0.1)
				(type default)
			)
			(layer "F.Fab")
		)
		(fp_line
			(start 0.120396 0.3048)
			(end 0.120396 0.2794)
			(stroke
				(width 0.1)
				(type default)
			)
			(layer "F.Fab")
		)
		(fp_line
			(start 0.67945 0.3048)
			(end 0.120396 0.3048)
			(stroke
				(width 0.1)
				(type default)
			)
			(layer "F.Fab")
		)
		(fp_line
			(start -0.12065 0.2794)
			(end -0.12065 0.3048)
			(stroke
				(width 0.1)
				(type default)
			)
			(layer "F.Fab")
		)
		(fp_line
			(start 0.120396 0.2794)
			(end -0.12065 0.2794)
			(stroke
				(width 0.1)
				(type default)
			)
			(layer "F.Fab")
		)
		(fp_line
			(start -0.12065 -0.2794)
			(end 0.12065 -0.2794)
			(stroke
				(width 0.1)
				(type default)
			)
			(layer "F.Fab")
		)
		(fp_line
			(start 0.12065 -0.2794)
			(end 0.12065 -0.3048)
			(stroke
				(width 0.1)
				(type default)
			)
			(layer "F.Fab")
		)
		(fp_line
			(start 0.12065 -0.3048)
			(end 0.67945 -0.3048)
			(stroke
				(width 0.1)
				(type default)
			)
			(layer "F.Fab")
		)
		(fp_line
			(start 0.67945 -0.3048)
			(end 0.67945 0.3048)
			(stroke
				(width 0.1)
				(type default)
			)
			(layer "F.Fab")
		)
		(fp_line
			(start -0.67945 -0.305054)
			(end -0.12065 -0.305054)
			(stroke
				(width 0.1)
				(type default)
			)
			(layer "F.Fab")
		)
		(fp_line
			(start -0.12065 -0.305054)
			(end -0.12065 -0.2794)
			(stroke
				(width 0.1)
				(type default)
			)
			(layer "F.Fab")
		)
		(pad "1" smd circle
			(at -0.40005 0 270)
			(size 0 0)
			(layers "F.Cu" "F.Mask" "F.Paste")
			(net "PCEPLL1_VDDA18_PEX1")
		)
		(pad "2" smd circle
			(at 0.40005 0 270)
			(size 0 0)
			(layers "F.Cu" "F.Mask" "F.Paste")
			(net "PCEPLL1_VDDA18_PEX1_R")
		)
	)
	(footprint ""
		(layer "F.Cu")
		(at 30.081982 -296.191432 180)
		(property "Reference" "C3030"
			(at 0 0 180)
			(layer "F.SilkS")
			(hide yes)
			(effects
				(font
					(size 1.27 1.27)
				)
			)
		)
		(property "Value" ""
			(at 0 0 180)
			(layer "F.Fab")
			(effects
				(font
					(size 1.27 1.27)
				)
			)
		)
		(duplicate_pad_numbers_are_jumpers no)
		(fp_line
			(start 1.2954 0.5842)
			(end -1.2954 0.5842)
			(stroke
				(width 0.1524)
				(type default)
			)
			(layer "F.SilkS")
		)
		(fp_line
			(start 1.2954 -0.5842)
			(end 1.2954 0.5842)
			(stroke
				(width 0.1524)
				(type default)
			)
			(layer "F.SilkS")
		)
		(fp_line
			(start -1.2954 0.5842)
			(end -1.2954 -0.5842)
			(stroke
				(width 0.1524)
				(type default)
			)
			(layer "F.SilkS")
		)
		(fp_line
			(start -1.2954 -0.5842)
			(end 1.2954 -0.5842)
			(stroke
				(width 0.1524)
				(type default)
			)
			(layer "F.SilkS")
		)
		(fp_line
			(start 1.1938 0.4064)
			(end 0.8636 0.4064)
			(stroke
				(width 0.1)
				(type default)
			)
			(layer "F.Fab")
		)
		(fp_line
			(start 1.1938 -0.4064)
			(end 1.1938 0.4064)
			(stroke
				(width 0.1)
				(type default)
			)
			(layer "F.Fab")
		)
		(fp_line
			(start 0.8636 0.4572)
			(end -0.8636 0.4572)
			(stroke
				(width 0.1)
				(type default)
			)
			(layer "F.Fab")
		)
		(fp_line
			(start 0.8636 0.4064)
			(end 0.8636 0.4572)
			(stroke
				(width 0.1)
				(type default)
			)
			(layer "F.Fab")
		)
		(fp_line
			(start 0.8636 -0.4064)
			(end 1.1938 -0.4064)
			(stroke
				(width 0.1)
				(type default)
			)
			(layer "F.Fab")
		)
		(fp_line
			(start 0.8636 -0.4572)
			(end 0.8636 -0.4064)
			(stroke
				(width 0.1)
				(type default)
			)
			(layer "F.Fab")
		)
		(fp_line
			(start -0.8636 0.4572)
			(end -0.8636 0.4064)
			(stroke
				(width 0.1)
				(type default)
			)
			(layer "F.Fab")
		)
		(fp_line
			(start -0.8636 0.4064)
			(end -1.1938 0.4064)
			(stroke
				(width 0.1)
				(type default)
			)
			(layer "F.Fab")
		)
		(fp_line
			(start -0.8636 -0.4064)
			(end -0.8636 -0.4572)
			(stroke
				(width 0.1)
				(type default)
			)
			(layer "F.Fab")
		)
		(fp_line
			(start -0.8636 -0.4572)
			(end 0.8636 -0.4572)
			(stroke
				(width 0.1)
				(type default)
			)
			(layer "F.Fab")
		)
		(fp_line
			(start -1.1938 0.4064)
			(end -1.1938 -0.4064)
			(stroke
				(width 0.1)
				(type default)
			)
			(layer "F.Fab")
		)
		(fp_line
			(start -1.1938 -0.4064)
			(end -0.8636 -0.4064)
			(stroke
				(width 0.1)
				(type default)
			)
			(layer "F.Fab")
		)
		(pad "1" smd rect
			(at -0.7366 0 90)
			(size 0.7112 0.8128)
			(layers "F.Cu" "F.Mask" "F.Paste")
			(net "PCEPLL0_VDDA18_PEX0_R")
		)
		(pad "2" smd rect
			(at 0.7366 0 90)
			(size 0.7112 0.8128)
			(layers "F.Cu" "F.Mask" "F.Paste")
			(net "GND")
		)
	)
	(footprint ""
		(layer "F.Cu")
		(at 240.316258 -219.674948)
		(property "Reference" "R4852"
			(at 0 0 0)
			(layer "F.SilkS")
			(hide yes)
			(effects
				(font
					(size 1.27 1.27)
				)
			)
		)
		(property "Value" ""
			(at 0 0 0)
			(layer "F.Fab")
			(effects
				(font
					(size 1.27 1.27)
				)
			)
		)
		(duplicate_pad_numbers_are_jumpers no)
		(fp_line
			(start -0.7874 -0.4064)
			(end 0.7874 -0.4064)
			(stroke
				(width 0.1524)
				(type default)
			)
			(layer "F.SilkS")
		)
		(fp_line
			(start -0.7874 0.4064)
			(end -0.7874 -0.4064)
			(stroke
				(width 0.1524)
				(type default)
			)
			(layer "F.SilkS")
		)
		(fp_line
			(start 0.7874 -0.4064)
			(end 0.7874 0.4064)
			(stroke
				(width 0.1524)
				(type default)
			)
			(layer "F.SilkS")
		)
		(fp_line
			(start 0.7874 0.4064)
			(end -0.7874 0.4064)
			(stroke
				(width 0.1524)
				(type default)
			)
			(layer "F.SilkS")
		)
		(fp_line
			(start -0.67945 -0.305054)
			(end -0.12065 -0.305054)
			(stroke
				(width 0.1)
				(type default)
			)
			(layer "F.Fab")
		)
		(fp_line
			(start -0.67945 0.3048)
			(end -0.67945 -0.305054)
			(stroke
				(width 0.1)
				(type default)
			)
			(layer "F.Fab")
		)
		(fp_line
			(start -0.12065 -0.305054)
			(end -0.12065 -0.2794)
			(stroke
				(width 0.1)
				(type default)
			)
			(layer "F.Fab")
		)
		(fp_line
			(start -0.12065 -0.2794)
			(end 0.12065 -0.2794)
			(stroke
				(width 0.1)
				(type default)
			)
			(layer "F.Fab")
		)
		(fp_line
			(start -0.12065 0.2794)
			(end -0.12065 0.3048)
			(stroke
				(width 0.1)
				(type default)
			)
			(layer "F.Fab")
		)
		(fp_line
			(start -0.12065 0.3048)
			(end -0.67945 0.3048)
			(stroke
				(width 0.1)
				(type default)
			)
			(layer "F.Fab")
		)
		(fp_line
			(start 0.120396 0.2794)
			(end -0.12065 0.2794)
			(stroke
				(width 0.1)
				(type default)
			)
			(layer "F.Fab")
		)
		(fp_line
			(start 0.120396 0.3048)
			(end 0.120396 0.2794)
			(stroke
				(width 0.1)
				(type default)
			)
			(layer "F.Fab")
		)
		(fp_line
			(start 0.12065 -0.3048)
			(end 0.67945 -0.3048)
			(stroke
				(width 0.1)
				(type default)
			)
			(layer "F.Fab")
		)
		(fp_line
			(start 0.12065 -0.2794)
			(end 0.12065 -0.3048)
			(stroke
				(width 0.1)
				(type default)
			)
			(layer "F.Fab")
		)
		(fp_line
			(start 0.67945 -0.3048)
			(end 0.67945 0.3048)
			(stroke
				(width 0.1)
				(type default)
			)
			(layer "F.Fab")
		)
		(fp_line
			(start 0.67945 0.3048)
			(end 0.120396 0.3048)
			(stroke
				(width 0.1)
				(type default)
			)
			(layer "F.Fab")
		)
		(pad "1" smd circle
			(at -0.40005 0)
			(size 0 0)
			(layers "F.Cu" "F.Mask" "F.Paste")
			(net "PD_BIC_ADCREXT0")
		)
		(pad "2" smd circle
			(at 0.40005 0)
			(size 0 0)
			(layers "F.Cu" "F.Mask" "F.Paste")
			(net "GND")
		)
	)
)
